FILE_TYPE = CONNECTIVITY;
{Allegro Design Entry HDL 17.2-2016 S081 (4005846) 1/11/2022}
"PAGE_NUMBER" = 188;
0"NC";
1"P1V05_PCH_AUX\g";
2"P3V3_AUX\g";
3"P3V3_AUX\g";
4"P3V3_AUX\g";
5"P3V3_AUX\g";
6"P3V3_AUX\g";
7"P1V05_PCH_AUX\g";
8"GND\g";
9"GND\g";
10"GND\g";
11"GND\g";
12"GND\g";
13"GND\g";
14"GND\g";
15"GND\g";
16"FM_PCH_SPARE0";
17"FM_PCH_MCRO_LDO";
18"FM_PCH_XTAL_INPUT_MODE_MGPIO_TEST3";
19"FM_PCH_RING_OSC_BYPASS_MGPIO_TEST2";
20"FM_BIOS_ADV_FUNCTIONS";
21"FM_MFG_MODE";
22"FM_XTAL_INPUT_FREQUENCY_1_MGPIO_TEST5";
23"FM_XTAL_INPUT_FREQUENCY_0_MGPIO_TEST4";
24"FM_PCH_DFXTESTMODE";
%"UNIVERSAL_GND"
"1","(-2925,2800)","0","logical_power","I20";
;
CDS_LIB"logical_power"
HDL_POWER"GND"
ROOM"IO_SLOT";
"A"15;
%"Q_RES"
"2","(-2925,3025)","0","pure_quanta","I21";
;
PART_NUMBER"CS31002FB08"
TOLERANCE"1%"
MATERIAL"CHIP"
WATTAGE"1/16W"
VALUE"10K"
PACK_TYPE"0402LF"
$LOCATION"R1299"
CDS_LIB"pure_quanta"
$LOCATION"R1299"
CDS_LOCATION"R1299"
$SEC"1"
CDS_SEC"1";
"A"
$PN"1"21;
"B"
$PN"2"15;
%"Q_RES"
"2","(-2925,3550)","0","pure_quanta","I22";
;
PART_NUMBER"CS21002FB06"
VALUE"1K"
WATTAGE"1/16W"
MATERIAL"EMPTY"
PACK_TYPE"0402LF"
TOLERANCE"1%"
$LOCATION"R1298"
CDS_LIB"pure_quanta"
$LOCATION"R1298"
CDS_LOCATION"R1298"
$SEC"1"
CDS_SEC"1";
"A"
$PN"1"7;
"B"
$PN"2"21;
%"UNIVERSAL_POWER"
"1","(-2925,3800)","0","logical_power","I23";
;
HDL_POWER"P1V05_PCH_AUX"
CDS_LIB"logical_power";
"A"7;
%"UNIVERSAL_GND"
"1","(-150,2800)","0","logical_power","I30";
;
CDS_LIB"logical_power"
HDL_POWER"GND"
ROOM"IO_SLOT";
"A"14;
%"Q_RES"
"2","(-150,3025)","0","pure_quanta","I31";
;
PART_NUMBER"CS31002FB08"
TOLERANCE"1%"
VALUE"10K"
WATTAGE"1/16W"
MATERIAL"CHIP"
PACK_TYPE"0402LF"
$LOCATION"R1311"
CDS_LIB"pure_quanta"
CDS_LOCATION"R1311"
$SEC"1"
CDS_SEC"1";
"A"
$PN"1"23;
"B"
$PN"2"14;
%"Q_RES"
"2","(3075,3025)","0","pure_quanta","I36";
;
PART_NUMBER"CS31002FB08"
VALUE"10K"
MATERIAL"CHIP"
PACK_TYPE"0402LF"
TOLERANCE"1%"
WATTAGE"1/16W"
$LOCATION"R1457"
CDS_LIB"pure_quanta"
CDS_LOCATION"R1457"
$SEC"1"
CDS_SEC"1";
"A"
$PN"1"22;
"B"
$PN"2"13;
%"UNIVERSAL_GND"
"1","(3075,2800)","0","logical_power","I37";
;
CDS_LIB"logical_power"
HDL_POWER"GND"
ROOM"IO_SLOT";
"A"13;
%"UNIVERSAL_POWER"
"1","(-150,1850)","0","logical_power","I39";
;
HDL_POWER"P3V3_AUX"
CDS_LIB"logical_power";
"A"6;
%"UNIVERSAL_GND"
"1","(-150,850)","0","logical_power","I42";
;
CDS_LIB"logical_power"
HDL_POWER"GND"
ROOM"IO_SLOT";
"A"12;
%"Q_RES"
"2","(-150,1075)","0","pure_quanta","I43";
;
PART_NUMBER"CS21002FB06"
PACK_TYPE"0402LF"
WATTAGE"1/16W"
TOLERANCE"1%"
MATERIAL"CHIP"
VALUE"1K"
$LOCATION"R1476"
CDS_LIB"pure_quanta"
CDS_LOCATION"R1476"
$SEC"1"
CDS_SEC"1";
"A"
$PN"1"19;
"B"
$PN"2"12;
%"Q_RES"
"2","(-150,1600)","0","pure_quanta","I44";
;
PART_NUMBER"CS21002FB06"
PACK_TYPE"0402LF"
MATERIAL"EMPTY"
WATTAGE"1/16W"
VALUE"1K"
TOLERANCE"1%"
$LOCATION"R1475"
CDS_LIB"pure_quanta"
CDS_LOCATION"R1475"
$SEC"1"
CDS_SEC"1";
"A"
$PN"1"6;
"B"
$PN"2"19;
%"UNIVERSAL_POWER"
"1","(3075,1850)","0","logical_power","I46";
;
HDL_POWER"P3V3_AUX"
CDS_LIB"logical_power";
"A"5;
%"Q_RES"
"2","(3075,1600)","0","pure_quanta","I47";
;
PART_NUMBER"CS21002FB06"
WATTAGE"1/16W"
VALUE"1K"
TOLERANCE"1%"
MATERIAL"EMPTY"
PACK_TYPE"0402LF"
$LOCATION"R1477"
CDS_LIB"pure_quanta"
CDS_LOCATION"R1477"
$SEC"1"
CDS_SEC"1";
"A"
$PN"1"5;
"B"
$PN"2"18;
%"UNIVERSAL_GND"
"1","(3075,850)","0","logical_power","I49";
;
CDS_LIB"logical_power"
HDL_POWER"GND"
ROOM"IO_SLOT";
"A"11;
%"Q_RES"
"2","(3075,1075)","0","pure_quanta","I50";
;
PART_NUMBER"CS31002FB08"
VALUE"10K"
TOLERANCE"1%"
WATTAGE"1/16W"
PACK_TYPE"0402LF"
MATERIAL"CHIP"
$LOCATION"R1478"
CDS_LIB"pure_quanta"
CDS_LOCATION"R1478"
$SEC"1"
CDS_SEC"1";
"A"
$PN"1"18;
"B"
$PN"2"11;
%"UNIVERSAL_POWER"
"1","(-2925,1875)","0","logical_power","I52";
;
HDL_POWER"P3V3_AUX"
CDS_LIB"logical_power";
"A"4;
%"Q_RES"
"2","(-2925,1625)","0","pure_quanta","I57";
;
PART_NUMBER"CS25112FB04"
TOLERANCE"1%"
VALUE"5.11K"
MATERIAL"CHIP"
PACK_TYPE"0402LF"
WATTAGE"1/16W"
$LOCATION"R3038"
CDS_LIB"pure_quanta"
CDS_LOCATION"R3038"
$SEC"1"
CDS_SEC"1";
"A"
$PN"1"4;
"B"
$PN"2"16;
%"UNIVERSAL_POWER"
"1","(-2950,-200)","0","logical_power","I60";
;
HDL_POWER"P3V3_AUX"
CDS_LIB"logical_power";
"A"3;
%"UNIVERSAL_GND"
"1","(-2950,-1200)","0","logical_power","I62";
;
CDS_LIB"logical_power"
HDL_POWER"GND"
ROOM"IO_SLOT";
"A"10;
%"Q_RES"
"2","(-2950,-450)","0","pure_quanta","I63";
;
PART_NUMBER"CS21002FB06"
MATERIAL"EMPTY"
TOLERANCE"1%"
PACK_TYPE"0402LF"
WATTAGE"1/16W"
VALUE"1K"
$LOCATION"R1220"
CDS_LIB"pure_quanta"
CDS_LOCATION"R1220"
$SEC"1"
CDS_SEC"1";
"A"
$PN"1"3;
"B"
$PN"2"17;
%"Q_RES"
"2","(-2950,-975)","0","pure_quanta","I64";
;
PART_NUMBER"CS21002FB06"
PACK_TYPE"0402LF"
MATERIAL"CHIP"
WATTAGE"1/16W"
VALUE"1K"
TOLERANCE"1%"
$LOCATION"R1221"
CDS_LIB"pure_quanta"
CDS_LOCATION"R1221"
$SEC"1"
CDS_SEC"1";
"A"
$PN"1"17;
"B"
$PN"2"10;
%"UNIVERSAL_POWER"
"1","(-150,-200)","0","logical_power","I67";
;
HDL_POWER"P3V3_AUX"
CDS_LIB"logical_power";
"A"2;
%"UNIVERSAL_GND"
"1","(-150,-1200)","0","logical_power","I69";
;
CDS_LIB"logical_power"
HDL_POWER"GND"
ROOM"IO_SLOT";
"A"9;
%"Q_RES"
"2","(-150,-975)","0","pure_quanta","I70";
;
PART_NUMBER"CS31202FB04"
TOLERANCE"1%"
VALUE"12K"
MATERIAL"EMPTY"
PACK_TYPE"0402LF"
WATTAGE"1/16W"
$LOCATION"R1497"
CDS_LIB"pure_quanta"
CDS_LOCATION"R1497"
$SEC"1"
CDS_SEC"1";
"A"
$PN"1"24;
"B"
$PN"2"9;
%"Q_RES"
"2","(-150,-450)","0","pure_quanta","I71";
;
PART_NUMBER"CS31002FB08"
TOLERANCE"1%"
PACK_TYPE"0402LF"
VALUE"10K"
WATTAGE"1/16W"
MATERIAL"CHIP"
$LOCATION"R1496"
CDS_LIB"pure_quanta"
CDS_LOCATION"R1496"
$SEC"1"
CDS_SEC"1";
"A"
$PN"1"2;
"B"
$PN"2"24;
%"UNIVERSAL_POWER"
"1","(3075,-200)","0","logical_power","I73";
;
HDL_POWER"P1V05_PCH_AUX"
CDS_LIB"logical_power";
"A"1;
%"UNIVERSAL_GND"
"1","(3075,-1200)","0","logical_power","I75";
;
CDS_LIB"logical_power"
HDL_POWER"GND"
ROOM"IO_SLOT";
"A"8;
%"Q_RES"
"2","(3075,-450)","0","pure_quanta","I76";
;
PART_NUMBER"CS21002FB06"
TOLERANCE"1%"
VALUE"1K"
WATTAGE"1/16W"
MATERIAL"EMPTY"
PACK_TYPE"0402LF"
$LOCATION"R1498"
CDS_LIB"pure_quanta"
CDS_LOCATION"R1498"
$SEC"1"
CDS_SEC"1";
"A"
$PN"1"1;
"B"
$PN"2"20;
%"Q_RES"
"2","(3075,-975)","0","pure_quanta","I77";
;
PART_NUMBER"CS21002FB06"
TOLERANCE"1%"
VALUE"1K"
PACK_TYPE"0402LF"
WATTAGE"1/16W"
MATERIAL"CHIP"
$LOCATION"R1499"
CDS_LIB"pure_quanta"
CDS_LOCATION"R1499"
$SEC"1"
CDS_SEC"1";
"A"
$PN"1"20;
"B"
$PN"2"8;
END.
